(kicad_pcb
	(version 20241229)
	(generator "pcbnew")
	(generator_version "9.0")
	(general
		(thickness 1.62)
		(legacy_teardrops no)
	)
	(paper "A3")
	(title_block
		(title "COM Express 7 Baseboard")
		(date "2025-02-04")
		(rev "1.1.2")
		(company "Antmicro Ltd")
		(comment 1 "www.antmicro.com")
		(comment 9 "footprints 68-68 of 802")
	)
	(layers
		(0 "F.Cu" signal)
		(4 "In1.Cu" signal)
		(6 "In2.Cu" signal)
		(8 "In3.Cu" signal)
		(10 "In4.Cu" signal)
		(12 "In5.Cu" signal)
		(14 "In6.Cu" signal)
		(2 "B.Cu" signal)
		(9 "F.Adhes" user "F.Adhesive")
		(11 "B.Adhes" user "B.Adhesive")
		(13 "F.Paste" user)
		(15 "B.Paste" user)
		(5 "F.SilkS" user "F.Silkscreen")
		(7 "B.SilkS" user "B.Silkscreen")
		(1 "F.Mask" user)
		(3 "B.Mask" user)
		(17 "Dwgs.User" user "User.Drawings")
		(19 "Cmts.User" user "User.Comments")
		(21 "Eco1.User" user "User.Eco1")
		(23 "Eco2.User" user "User.Eco2")
		(25 "Edge.Cuts" user)
		(27 "Margin" user)
		(31 "F.CrtYd" user "F.Courtyard")
		(29 "B.CrtYd" user "B.Courtyard")
		(35 "F.Fab" user)
		(33 "B.Fab" user)
	)
	(footprint "antmicro-footprints:PCB-Edge_Samtec_HSEC8_2x20_HSEC8-120-01-S-D-EM2"
		(layer "F.Cu")
		(at 317.95 160.51 -90)
		(property "Reference" "J16"
			(at -7.31 2.62 0)
			(unlocked yes)
			(layer "F.SilkS")
			(effects
				(font
					(size 0.7 0.7)
					(thickness 0.15)
				)
				(justify left bottom)
			)
		)
		(property "Value" "PCB-Edge_Samtec_HSEC8_2x20_HSEC8-120-01-S-D-EM2"
			(at 0 4 270)
			(unlocked yes)
			(layer "F.Fab")
			(effects
				(font
					(size 0.7 0.7)
					(thickness 0.15)
				)
				(justify left bottom)
			)
		)
		(property "Datasheet" "https://suddendocs.samtec.com/prints/hsec8-1xxx-xx-xx-dv-x-xx-footprint.pdf"
			(at 0 0 90)
			(layer "F.Fab")
			(hide yes)
			(effects
				(font
					(size 1.27 1.27)
					(thickness 0.15)
				)
			)
		)
		(property "Author" "Antmicro"
			(at 0 0 270)
			(unlocked yes)
			(layer "F.Fab")
			(hide yes)
			(effects
				(font
					(size 1 1)
					(thickness 0.15)
				)
			)
		)
		(property "License" "Apache-2.0"
			(at 0 0 270)
			(unlocked yes)
			(layer "F.Fab")
			(hide yes)
			(effects
				(font
					(size 1 1)
					(thickness 0.15)
				)
			)
		)
		(property "Public" "False"
			(at 0 0 270)
			(unlocked yes)
			(layer "F.Fab")
			(hide yes)
			(effects
				(font
					(size 1 1)
					(thickness 0.15)
				)
			)
		)
		(sheetname "Backplane")
		(sheetfile "backplane.kicad_sch")
		(attr exclude_from_pos_files exclude_from_bom)
		(fp_poly
			(pts
				(xy -7.6 0.6) (xy -8 1.2) (xy -7.2 1.2)
			)
			(stroke
				(width 0.1)
				(type solid)
			)
			(fill yes)
			(layer "B.SilkS")
		)
		(fp_line
			(start -9.725 2.52)
			(end -11.225 2.52)
			(stroke
				(width 0.05)
				(type default)
			)
			(layer "Edge.Cuts")
		)
		(fp_line
			(start 9.525 2.52)
			(end 11.025 2.52)
			(stroke
				(width 0.05)
				(type default)
			)
			(layer "Edge.Cuts")
		)
		(fp_line
			(start -8.725 1.52)
			(end -8.725 0)
			(stroke
				(width 0.05)
				(type default)
			)
			(layer "Edge.Cuts")
		)
		(fp_line
			(start 8.525 1.52)
			(end 8.525 0)
			(stroke
				(width 0.05)
				(type default)
			)
			(layer "Edge.Cuts")
		)
		(fp_line
			(start -8.725 -4)
			(end -8.725 0)
			(stroke
				(width 0.05)
				(type default)
			)
			(layer "Edge.Cuts")
		)
		(fp_line
			(start -8.725 -4)
			(end 8.525 -4)
			(stroke
				(width 0.05)
				(type default)
			)
			(layer "Edge.Cuts")
		)
		(fp_line
			(start 8.525 -4)
			(end 8.525 0)
			(stroke
				(width 0.05)
				(type default)
			)
			(layer "Edge.Cuts")
		)
		(fp_arc
			(start 9.525 2.52)
			(mid 8.817999 2.227001)
			(end 8.525 1.52)
			(stroke
				(width 0.05)
				(type default)
			)
			(layer "Edge.Cuts")
		)
		(fp_arc
			(start -8.725 1.52)
			(mid -9.018 2.227)
			(end -9.725 2.52)
			(stroke
				(width 0.05)
				(type default)
			)
			(layer "Edge.Cuts")
		)
		(pad "1" smd roundrect
			(at -7.6 -1.5 180)
			(size 3 0.55)
			(layers "B.Cu" "B.Mask")
			(roundrect_rratio 0.25)
			(net 144 "VCC")
			(pintype "passive")
			(teardrops
				(best_length_ratio 0.2)
				(max_length 1)
				(best_width_ratio 0.9)
				(max_width 2)
				(curved_edges yes)
				(filter_ratio 0.9)
				(enabled yes)
				(allow_two_segments yes)
				(prefer_zone_connections yes)
			)
		)
		(pad "2" smd roundrect
			(at -7.6 -1.5)
			(size 3 0.55)
			(layers "F.Cu" "F.Mask")
			(roundrect_rratio 0.25)
			(net 144 "VCC")
			(pintype "passive")
			(teardrops
				(best_length_ratio 0.2)
				(max_length 1)
				(best_width_ratio 0.9)
				(max_width 2)
				(curved_edges yes)
				(filter_ratio 0.9)
				(enabled yes)
				(allow_two_segments yes)
				(prefer_zone_connections yes)
			)
		)
		(pad "3" smd roundrect
			(at -6.8 -1.5 180)
			(size 3 0.55)
			(layers "B.Cu" "B.Mask")
			(roundrect_rratio 0.25)
			(net 144 "VCC")
			(pintype "passive")
			(teardrops
				(best_length_ratio 0.2)
				(max_length 1)
				(best_width_ratio 0.9)
				(max_width 2)
				(curved_edges yes)
				(filter_ratio 0.9)
				(enabled yes)
				(allow_two_segments yes)
				(prefer_zone_connections yes)
			)
		)
		(pad "4" smd roundrect
			(at -6.8 -1.5)
			(size 3 0.55)
			(layers "F.Cu" "F.Mask")
			(roundrect_rratio 0.25)
			(net 144 "VCC")
			(pintype "passive")
			(teardrops
				(best_length_ratio 0.2)
				(max_length 1)
				(best_width_ratio 0.9)
				(max_width 2)
				(curved_edges yes)
				(filter_ratio 0.9)
				(enabled yes)
				(allow_two_segments yes)
				(prefer_zone_connections yes)
			)
		)
		(pad "5" smd roundrect
			(at -6 -1.5 180)
			(size 3 0.55)
			(layers "B.Cu" "B.Mask")
			(roundrect_rratio 0.25)
			(net 144 "VCC")
			(pintype "passive")
			(teardrops
				(best_length_ratio 0.2)
				(max_length 1)
				(best_width_ratio 0.9)
				(max_width 2)
				(curved_edges yes)
				(filter_ratio 0.9)
				(enabled yes)
				(allow_two_segments yes)
				(prefer_zone_connections yes)
			)
		)
		(pad "6" smd roundrect
			(at -6 -1.5)
			(size 3 0.55)
			(layers "F.Cu" "F.Mask")
			(roundrect_rratio 0.25)
			(net 144 "VCC")
			(pintype "passive")
			(teardrops
				(best_length_ratio 0.2)
				(max_length 1)
				(best_width_ratio 0.9)
				(max_width 2)
				(curved_edges yes)
				(filter_ratio 0.9)
				(enabled yes)
				(allow_two_segments yes)
				(prefer_zone_connections yes)
			)
		)
		(pad "7" smd roundrect
			(at -5.2 -1.5 180)
			(size 3 0.55)
			(layers "B.Cu" "B.Mask")
			(roundrect_rratio 0.25)
			(net 144 "VCC")
			(pintype "passive")
			(teardrops
				(best_length_ratio 0.2)
				(max_length 1)
				(best_width_ratio 0.9)
				(max_width 2)
				(curved_edges yes)
				(filter_ratio 0.9)
				(enabled yes)
				(allow_two_segments yes)
				(prefer_zone_connections yes)
			)
		)
		(pad "8" smd roundrect
			(at -5.2 -1.5)
			(size 3 0.55)
			(layers "F.Cu" "F.Mask")
			(roundrect_rratio 0.25)
			(net 144 "VCC")
			(pintype "passive")
			(teardrops
				(best_length_ratio 0.2)
				(max_length 1)
				(best_width_ratio 0.9)
				(max_width 2)
				(curved_edges yes)
				(filter_ratio 0.9)
				(enabled yes)
				(allow_two_segments yes)
				(prefer_zone_connections yes)
			)
		)
		(pad "9" smd roundrect
			(at -4.4 -1.5 180)
			(size 3 0.55)
			(layers "B.Cu" "B.Mask")
			(roundrect_rratio 0.25)
			(net 144 "VCC")
			(pintype "passive")
			(teardrops
				(best_length_ratio 0.2)
				(max_length 1)
				(best_width_ratio 0.9)
				(max_width 2)
				(curved_edges yes)
				(filter_ratio 0.9)
				(enabled yes)
				(allow_two_segments yes)
				(prefer_zone_connections yes)
			)
		)
		(pad "10" smd roundrect
			(at -4.4 -1.5)
			(size 3 0.55)
			(layers "F.Cu" "F.Mask")
			(roundrect_rratio 0.25)
			(net 144 "VCC")
			(pintype "passive")
			(teardrops
				(best_length_ratio 0.2)
				(max_length 1)
				(best_width_ratio 0.9)
				(max_width 2)
				(curved_edges yes)
				(filter_ratio 0.9)
				(enabled yes)
				(allow_two_segments yes)
				(prefer_zone_connections yes)
			)
		)
		(pad "11" smd roundrect
			(at -3.6 -1.5 180)
			(size 3 0.55)
			(layers "B.Cu" "B.Mask")
			(roundrect_rratio 0.25)
			(net 1 "GND")
			(pintype "passive")
			(teardrops
				(best_length_ratio 0.2)
				(max_length 1)
				(best_width_ratio 0.9)
				(max_width 2)
				(curved_edges yes)
				(filter_ratio 0.9)
				(enabled yes)
				(allow_two_segments yes)
				(prefer_zone_connections yes)
			)
		)
		(pad "12" smd roundrect
			(at -3.6 -1.5)
			(size 3 0.55)
			(layers "F.Cu" "F.Mask")
			(roundrect_rratio 0.25)
			(net 1 "GND")
			(pintype "passive")
			(teardrops
				(best_length_ratio 0.2)
				(max_length 1)
				(best_width_ratio 0.9)
				(max_width 2)
				(curved_edges yes)
				(filter_ratio 0.9)
				(enabled yes)
				(allow_two_segments yes)
				(prefer_zone_connections yes)
			)
		)
		(pad "13" smd roundrect
			(at -2.8 -1.5 180)
			(size 3 0.55)
			(layers "B.Cu" "B.Mask")
			(roundrect_rratio 0.25)
			(net 1 "GND")
			(pintype "passive")
			(teardrops
				(best_length_ratio 0.2)
				(max_length 1)
				(best_width_ratio 0.9)
				(max_width 2)
				(curved_edges yes)
				(filter_ratio 0.9)
				(enabled yes)
				(allow_two_segments yes)
				(prefer_zone_connections yes)
			)
		)
		(pad "14" smd roundrect
			(at -2.8 -1.5)
			(size 3 0.55)
			(layers "F.Cu" "F.Mask")
			(roundrect_rratio 0.25)
			(net 1 "GND")
			(pintype "passive")
			(teardrops
				(best_length_ratio 0.2)
				(max_length 1)
				(best_width_ratio 0.9)
				(max_width 2)
				(curved_edges yes)
				(filter_ratio 0.9)
				(enabled yes)
				(allow_two_segments yes)
				(prefer_zone_connections yes)
			)
		)
		(pad "15" smd roundrect
			(at -2 -1.5 180)
			(size 3 0.55)
			(layers "B.Cu" "B.Mask")
			(roundrect_rratio 0.25)
			(net 1 "GND")
			(pintype "passive")
			(teardrops
				(best_length_ratio 0.2)
				(max_length 1)
				(best_width_ratio 0.9)
				(max_width 2)
				(curved_edges yes)
				(filter_ratio 0.9)
				(enabled yes)
				(allow_two_segments yes)
				(prefer_zone_connections yes)
			)
		)
		(pad "16" smd roundrect
			(at -2 -1.5)
			(size 3 0.55)
			(layers "F.Cu" "F.Mask")
			(roundrect_rratio 0.25)
			(net 1 "GND")
			(pintype "passive")
			(teardrops
				(best_length_ratio 0.2)
				(max_length 1)
				(best_width_ratio 0.9)
				(max_width 2)
				(curved_edges yes)
				(filter_ratio 0.9)
				(enabled yes)
				(allow_two_segments yes)
				(prefer_zone_connections yes)
			)
		)
		(pad "17" smd roundrect
			(at -1.2 -1.5 180)
			(size 3 0.55)
			(layers "B.Cu" "B.Mask")
			(roundrect_rratio 0.25)
			(net 866 "/Backplane/PCIe_{x2}.TX0+")
			(pintype "passive")
			(teardrops
				(best_length_ratio 0.2)
				(max_length 1)
				(best_width_ratio 0.9)
				(max_width 2)
				(curved_edges yes)
				(filter_ratio 0.9)
				(enabled yes)
				(allow_two_segments yes)
				(prefer_zone_connections yes)
			)
		)
		(pad "18" smd roundrect
			(at -1.2 -1.5)
			(size 3 0.55)
			(layers "F.Cu" "F.Mask")
			(roundrect_rratio 0.25)
			(net 532 "/Backplane/PCIe_{x2}.RX0+")
			(pintype "passive")
			(teardrops
				(best_length_ratio 0.2)
				(max_length 1)
				(best_width_ratio 0.9)
				(max_width 2)
				(curved_edges yes)
				(filter_ratio 0.9)
				(enabled yes)
				(allow_two_segments yes)
				(prefer_zone_connections yes)
			)
		)
		(pad "19" smd roundrect
			(at -0.4 -1.5 180)
			(size 3 0.55)
			(layers "B.Cu" "B.Mask")
			(roundrect_rratio 0.25)
			(net 867 "/Backplane/PCIe_{x2}.TX0-")
			(pintype "passive")
			(teardrops
				(best_length_ratio 0.2)
				(max_length 1)
				(best_width_ratio 0.9)
				(max_width 2)
				(curved_edges yes)
				(filter_ratio 0.9)
				(enabled yes)
				(allow_two_segments yes)
				(prefer_zone_connections yes)
			)
		)
		(pad "20" smd roundrect
			(at -0.4 -1.5)
			(size 3 0.55)
			(layers "F.Cu" "F.Mask")
			(roundrect_rratio 0.25)
			(net 537 "/Backplane/PCIe_{x2}.RX0-")
			(pintype "passive")
			(teardrops
				(best_length_ratio 0.2)
				(max_length 1)
				(best_width_ratio 0.9)
				(max_width 2)
				(curved_edges yes)
				(filter_ratio 0.9)
				(enabled yes)
				(allow_two_segments yes)
				(prefer_zone_connections yes)
			)
		)
		(pad "21" smd roundrect
			(at 0.4 -1.5 180)
			(size 3 0.55)
			(layers "B.Cu" "B.Mask")
			(roundrect_rratio 0.25)
			(net 1 "GND")
			(pintype "passive")
			(teardrops
				(best_length_ratio 0.2)
				(max_length 1)
				(best_width_ratio 0.9)
				(max_width 2)
				(curved_edges yes)
				(filter_ratio 0.9)
				(enabled yes)
				(allow_two_segments yes)
				(prefer_zone_connections yes)
			)
		)
		(pad "22" smd roundrect
			(at 0.4 -1.5)
			(size 3 0.55)
			(layers "F.Cu" "F.Mask")
			(roundrect_rratio 0.25)
			(net 1 "GND")
			(pintype "passive")
			(teardrops
				(best_length_ratio 0.2)
				(max_length 1)
				(best_width_ratio 0.9)
				(max_width 2)
				(curved_edges yes)
				(filter_ratio 0.9)
				(enabled yes)
				(allow_two_segments yes)
				(prefer_zone_connections yes)
			)
		)
		(pad "23" smd roundrect
			(at 1.2 -1.5 180)
			(size 3 0.55)
			(layers "B.Cu" "B.Mask")
			(roundrect_rratio 0.25)
			(net 868 "/Backplane/PCIe_{x2}.TX1+")
			(pintype "passive")
			(teardrops
				(best_length_ratio 0.2)
				(max_length 1)
				(best_width_ratio 0.9)
				(max_width 2)
				(curved_edges yes)
				(filter_ratio 0.9)
				(enabled yes)
				(allow_two_segments yes)
				(prefer_zone_connections yes)
			)
		)
		(pad "24" smd roundrect
			(at 1.2 -1.5)
			(size 3 0.55)
			(layers "F.Cu" "F.Mask")
			(roundrect_rratio 0.25)
			(net 771 "/Backplane/PCIe_{x2}.RX1+")
			(pintype "passive")
			(teardrops
				(best_length_ratio 0.2)
				(max_length 1)
				(best_width_ratio 0.9)
				(max_width 2)
				(curved_edges yes)
				(filter_ratio 0.9)
				(enabled yes)
				(allow_two_segments yes)
				(prefer_zone_connections yes)
			)
		)
		(pad "25" smd roundrect
			(at 2 -1.5 180)
			(size 3 0.55)
			(layers "B.Cu" "B.Mask")
			(roundrect_rratio 0.25)
			(net 869 "/Backplane/PCIe_{x2}.TX1-")
			(pintype "passive")
			(teardrops
				(best_length_ratio 0.2)
				(max_length 1)
				(best_width_ratio 0.9)
				(max_width 2)
				(curved_edges yes)
				(filter_ratio 0.9)
				(enabled yes)
				(allow_two_segments yes)
				(prefer_zone_connections yes)
			)
		)
		(pad "26" smd roundrect
			(at 2 -1.5)
			(size 3 0.55)
			(layers "F.Cu" "F.Mask")
			(roundrect_rratio 0.25)
			(net 772 "/Backplane/PCIe_{x2}.RX1-")
			(pintype "passive")
			(teardrops
				(best_length_ratio 0.2)
				(max_length 1)
				(best_width_ratio 0.9)
				(max_width 2)
				(curved_edges yes)
				(filter_ratio 0.9)
				(enabled yes)
				(allow_two_segments yes)
				(prefer_zone_connections yes)
			)
		)
		(pad "27" smd roundrect
			(at 2.8 -1.5 180)
			(size 3 0.55)
			(layers "B.Cu" "B.Mask")
			(roundrect_rratio 0.25)
			(net 1 "GND")
			(pintype "passive")
			(teardrops
				(best_length_ratio 0.2)
				(max_length 1)
				(best_width_ratio 0.9)
				(max_width 2)
				(curved_edges yes)
				(filter_ratio 0.9)
				(enabled yes)
				(allow_two_segments yes)
				(prefer_zone_connections yes)
			)
		)
		(pad "28" smd roundrect
			(at 2.8 -1.5)
			(size 3 0.55)
			(layers "F.Cu" "F.Mask")
			(roundrect_rratio 0.25)
			(net 1 "GND")
			(pintype "passive")
			(teardrops
				(best_length_ratio 0.2)
				(max_length 1)
				(best_width_ratio 0.9)
				(max_width 2)
				(curved_edges yes)
				(filter_ratio 0.9)
				(enabled yes)
				(allow_two_segments yes)
				(prefer_zone_connections yes)
			)
		)
		(pad "29" smd roundrect
			(at 3.6 -1.5 180)
			(size 3 0.55)
			(layers "B.Cu" "B.Mask")
			(roundrect_rratio 0.25)
			(net 203 "/Backplane/PCIe_{REF}.CK+")
			(pintype "passive")
			(teardrops
				(best_length_ratio 0.2)
				(max_length 1)
				(best_width_ratio 0.9)
				(max_width 2)
				(curved_edges yes)
				(filter_ratio 0.9)
				(enabled yes)
				(allow_two_segments yes)
				(prefer_zone_connections yes)
			)
		)
		(pad "30" smd roundrect
			(at 3.6 -1.5)
			(size 3 0.55)
			(layers "F.Cu" "F.Mask")
			(roundrect_rratio 0.25)
			(net 528 "/Backplane/~{PERST}")
			(pintype "passive")
			(teardrops
				(best_length_ratio 0.2)
				(max_length 1)
				(best_width_ratio 0.9)
				(max_width 2)
				(curved_edges yes)
				(filter_ratio 0.9)
				(enabled yes)
				(allow_two_segments yes)
				(prefer_zone_connections yes)
			)
		)
		(pad "31" smd roundrect
			(at 4.4 -1.5 180)
			(size 3 0.55)
			(layers "B.Cu" "B.Mask")
			(roundrect_rratio 0.25)
			(net 205 "/Backplane/PCIe_{REF}.CK-")
			(pintype "passive")
			(teardrops
				(best_length_ratio 0.2)
				(max_length 1)
				(best_width_ratio 0.9)
				(max_width 2)
				(curved_edges yes)
				(filter_ratio 0.9)
				(enabled yes)
				(allow_two_segments yes)
				(prefer_zone_connections yes)
			)
		)
		(pad "32" smd roundrect
			(at 4.4 -1.5)
			(size 3 0.55)
			(layers "F.Cu" "F.Mask")
			(roundrect_rratio 0.25)
			(net 526 "/Backplane/~{PRSNT}")
			(pintype "passive")
			(teardrops
				(best_length_ratio 0.2)
				(max_length 1)
				(best_width_ratio 0.9)
				(max_width 2)
				(curved_edges yes)
				(filter_ratio 0.9)
				(enabled yes)
				(allow_two_segments yes)
				(prefer_zone_connections yes)
			)
		)
		(pad "33" smd roundrect
			(at 5.2 -1.5 180)
			(size 3 0.55)
			(layers "B.Cu" "B.Mask")
			(roundrect_rratio 0.25)
			(net 1 "GND")
			(pintype "passive")
			(teardrops
				(best_length_ratio 0.2)
				(max_length 1)
				(best_width_ratio 0.9)
				(max_width 2)
				(curved_edges yes)
				(filter_ratio 0.9)
				(enabled yes)
				(allow_two_segments yes)
				(prefer_zone_connections yes)
			)
		)
		(pad "34" smd roundrect
			(at 5.2 -1.5)
			(size 3 0.55)
			(layers "F.Cu" "F.Mask")
			(roundrect_rratio 0.25)
			(net 527 "/Backplane/GPIO")
			(pintype "passive")
			(teardrops
				(best_length_ratio 0.2)
				(max_length 1)
				(best_width_ratio 0.9)
				(max_width 2)
				(curved_edges yes)
				(filter_ratio 0.9)
				(enabled yes)
				(allow_two_segments yes)
				(prefer_zone_connections yes)
			)
		)
		(pad "35" smd roundrect
			(at 6 -1.5 180)
			(size 3 0.55)
			(layers "B.Cu" "B.Mask")
			(roundrect_rratio 0.25)
			(net 206 "/Backplane/USB.D+")
			(pintype "passive")
			(teardrops
				(best_length_ratio 0.2)
				(max_length 1)
				(best_width_ratio 0.9)
				(max_width 2)
				(curved_edges yes)
				(filter_ratio 0.9)
				(enabled yes)
				(allow_two_segments yes)
				(prefer_zone_connections yes)
			)
		)
		(pad "36" smd roundrect
			(at 6 -1.5)
			(size 3 0.55)
			(layers "F.Cu" "F.Mask")
			(roundrect_rratio 0.25)
			(net 208 "/Backplane/UART.RX")
			(pintype "passive")
			(teardrops
				(best_length_ratio 0.2)
				(max_length 1)
				(best_width_ratio 0.9)
				(max_width 2)
				(curved_edges yes)
				(filter_ratio 0.9)
				(enabled yes)
				(allow_two_segments yes)
				(prefer_zone_connections yes)
			)
		)
		(pad "37" smd roundrect
			(at 6.8 -1.5 180)
			(size 3 0.55)
			(layers "B.Cu" "B.Mask")
			(roundrect_rratio 0.25)
			(net 204 "/Backplane/USB.D-")
			(pintype "passive")
			(teardrops
				(best_length_ratio 0.2)
				(max_length 1)
				(best_width_ratio 0.9)
				(max_width 2)
				(curved_edges yes)
				(filter_ratio 0.9)
				(enabled yes)
				(allow_two_segments yes)
				(prefer_zone_connections yes)
			)
		)
		(pad "38" smd roundrect
			(at 6.8 -1.5)
			(size 3 0.55)
			(layers "F.Cu" "F.Mask")
			(roundrect_rratio 0.25)
			(net 207 "/Backplane/UART.TX")
			(pintype "passive")
			(teardrops
				(best_length_ratio 0.2)
				(max_length 1)
				(best_width_ratio 0.9)
				(max_width 2)
				(curved_edges yes)
				(filter_ratio 0.9)
				(enabled yes)
				(allow_two_segments yes)
				(prefer_zone_connections yes)
			)
		)
		(pad "39" smd roundrect
			(at 7.6 -1.5 180)
			(size 3 0.55)
			(layers "B.Cu" "B.Mask")
			(roundrect_rratio 0.25)
			(net 1 "GND")
			(pintype "passive")
			(teardrops
				(best_length_ratio 0.2)
				(max_length 1)
				(best_width_ratio 0.9)
				(max_width 2)
				(curved_edges yes)
				(filter_ratio 0.9)
				(enabled yes)
				(allow_two_segments yes)
				(prefer_zone_connections yes)
			)
		)
		(pad "40" smd roundrect
			(at 7.6 -1.5)
			(size 3 0.55)
			(layers "F.Cu" "F.Mask")
			(roundrect_rratio 0.25)
			(net 1 "GND")
			(pintype "passive")
			(teardrops
				(best_length_ratio 0.2)
				(max_length 1)
				(best_width_ratio 0.9)
				(max_width 2)
				(curved_edges yes)
				(filter_ratio 0.9)
				(enabled yes)
				(allow_two_segments yes)
				(prefer_zone_connections yes)
			)
		)
	)
)
